# S9S_MB_2U (Grand Teton) — schematic netlist excerpt (pin names and nets, part order shuffled) for the footprints in the layout excerpt that follows; sources: Cadence DE-HDL packaged netlist, KiCad conversion of 03242023_DA0F0TMBIJ0_F0T_Motherboard_J_brd_V01_OCP.brd

C877  Q_CAP_DIFFBUS  DIFF BUS_0.22UF 6.3V 20% X6S  pkg C0201  page 174 : \1\ = P5E_CPU0_PE3_TX_C_DP<12> ; \2\ = P5E_CPU0_PE3_TX_DP<12>
C285  Q_CAP  22UF 4V 20% X6S  pkg C0402  page 77 : A = PVCCIN_CPU1 ; B = GND

U321  74LVC1G66GV  IC  pkg SC74AXA  page 161
  Y  = CLK_50M_NCSI_OCP_V3_2
  Z  = CLK_50M_NCSI_OCP_V3_2_ISO_R
  GND  = GND
  E  = FB_BMC_ISOLATE1
  VCC  = P3V3_AUX

(kicad_pcb
	(version 20260206)
	(generator "pcbnew")
	(generator_version "10.0")
	(general
		(thickness 1.6)
		(legacy_teardrops no)
	)
	(paper "A4")
	(title_block
		(title "03242023_DA0F0TMBIJ0_F0T_Motherboard_J_brd_V01_OCP.brd")
		(comment 1 "Grand Teton / footprints 2845-2847 of 6105")
	)
	(layers
		(0 "F.Cu" signal "TOP")
		(4 "In1.Cu" signal "GND")
		(6 "In2.Cu" signal "IN1")
		(8 "In3.Cu" signal "GND1")
		(10 "In4.Cu" signal "IN2")
		(12 "In5.Cu" signal "GND2")
		(14 "In6.Cu" signal "IN3")
		(16 "In7.Cu" signal "GND3")
		(18 "In8.Cu" signal "VCC")
		(20 "In9.Cu" signal "VCC1")
		(22 "In10.Cu" signal "GND4")
		(24 "In11.Cu" signal "IN4")
		(26 "In12.Cu" signal "GND5")
		(28 "In13.Cu" signal "IN5")
		(30 "In14.Cu" signal "GND6")
		(32 "In15.Cu" signal "IN6")
		(34 "In16.Cu" signal "GND7")
		(2 "B.Cu" signal "BOTTOM")
		(9 "F.Adhes" user "F.Adhesive")
		(11 "B.Adhes" user "B.Adhesive")
		(13 "F.Paste" user "Package Geometry/Pastemask Top")
		(15 "B.Paste" user "Package Geometry/Pastemask Bottom")
		(5 "F.SilkS" user "Ref Des/Silkscreen Top")
		(7 "B.SilkS" user "Ref Des/Silkscreen Bottom")
		(1 "F.Mask" user "Board Geometry/Soldermask Top")
		(3 "B.Mask" user "Board Geometry/Soldermask Bottom")
		(17 "Dwgs.User" user "User.Drawings")
		(19 "Cmts.User" user "User.Comments")
		(21 "Eco1.User" user "User.Eco1")
		(23 "Eco2.User" user "User.Eco2")
		(25 "Edge.Cuts" user "Board Geometry/Outline")
		(27 "Margin" user)
		(31 "F.CrtYd" user "Package Geometry/Place Bound Top")
		(29 "B.CrtYd" user "Package Geometry/Place Bound Bottom")
		(35 "F.Fab" user "Ref Des/Assembly Top")
		(33 "B.Fab" user "Ref Des/Assembly Bottom")
	)
	(footprint ""
		(layer "F.Cu")
		(at 117.526816 -256.6543 -90)
		(property "Reference" "C285"
			(at 0 0 270)
			(layer "F.SilkS")
			(hide yes)
			(effects
				(font
					(size 1.27 1.27)
				)
			)
		)
		(property "Value" ""
			(at 0 0 270)
			(layer "F.Fab")
			(effects
				(font
					(size 1.27 1.27)
				)
			)
		)
		(duplicate_pad_numbers_are_jumpers no)
		(fp_line
			(start -0.7874 0.4064)
			(end -0.7874 -0.4064)
			(stroke
				(width 0.1524)
				(type default)
			)
			(layer "F.SilkS")
		)
		(fp_line
			(start 0.7874 0.4064)
			(end -0.7874 0.4064)
			(stroke
				(width 0.1524)
				(type default)
			)
			(layer "F.SilkS")
		)
		(fp_line
			(start -0.7874 -0.4064)
			(end 0.7874 -0.4064)
			(stroke
				(width 0.1524)
				(type default)
			)
			(layer "F.SilkS")
		)
		(fp_line
			(start 0.7874 -0.4064)
			(end 0.7874 0.4064)
			(stroke
				(width 0.1524)
				(type default)
			)
			(layer "F.SilkS")
		)
		(fp_line
			(start -0.67945 0.3048)
			(end -0.67945 -0.305054)
			(stroke
				(width 0.1)
				(type default)
			)
			(layer "F.Fab")
		)
		(fp_line
			(start -0.12065 0.3048)
			(end -0.67945 0.3048)
			(stroke
				(width 0.1)
				(type default)
			)
			(layer "F.Fab")
		)
		(fp_line
			(start 0.120396 0.3048)
			(end 0.120396 0.2794)
			(stroke
				(width 0.1)
				(type default)
			)
			(layer "F.Fab")
		)
		(fp_line
			(start 0.67945 0.3048)
			(end 0.120396 0.3048)
			(stroke
				(width 0.1)
				(type default)
			)
			(layer "F.Fab")
		)
		(fp_line
			(start -0.12065 0.2794)
			(end -0.12065 0.3048)
			(stroke
				(width 0.1)
				(type default)
			)
			(layer "F.Fab")
		)
		(fp_line
			(start 0.120396 0.2794)
			(end -0.12065 0.2794)
			(stroke
				(width 0.1)
				(type default)
			)
			(layer "F.Fab")
		)
		(fp_line
			(start -0.12065 -0.2794)
			(end 0.12065 -0.2794)
			(stroke
				(width 0.1)
				(type default)
			)
			(layer "F.Fab")
		)
		(fp_line
			(start 0.12065 -0.2794)
			(end 0.12065 -0.3048)
			(stroke
				(width 0.1)
				(type default)
			)
			(layer "F.Fab")
		)
		(fp_line
			(start 0.12065 -0.3048)
			(end 0.67945 -0.3048)
			(stroke
				(width 0.1)
				(type default)
			)
			(layer "F.Fab")
		)
		(fp_line
			(start 0.67945 -0.3048)
			(end 0.67945 0.3048)
			(stroke
				(width 0.1)
				(type default)
			)
			(layer "F.Fab")
		)
		(fp_line
			(start -0.67945 -0.305054)
			(end -0.12065 -0.305054)
			(stroke
				(width 0.1)
				(type default)
			)
			(layer "F.Fab")
		)
		(fp_line
			(start -0.12065 -0.305054)
			(end -0.12065 -0.2794)
			(stroke
				(width 0.1)
				(type default)
			)
			(layer "F.Fab")
		)
		(pad "1" smd circle
			(at -0.40005 0 270)
			(size 0 0)
			(layers "F.Cu" "F.Mask" "F.Paste")
			(net "PVCCIN_CPU1")
		)
		(pad "2" smd circle
			(at 0.40005 0 270)
			(size 0 0)
			(layers "F.Cu" "F.Mask" "F.Paste")
			(net "GND")
		)
	)
	(footprint ""
		(layer "F.Cu")
		(at 382.84785 -408.517344 -90)
		(property "Reference" "C877"
			(at 0 0 270)
			(layer "F.SilkS")
			(hide yes)
			(effects
				(font
					(size 1.27 1.27)
				)
			)
		)
		(property "Value" ""
			(at 0 0 270)
			(layer "F.Fab")
			(effects
				(font
					(size 1.27 1.27)
				)
			)
		)
		(duplicate_pad_numbers_are_jumpers no)
		(fp_line
			(start -0.299974 0.150114)
			(end -0.299974 -0.150114)
			(stroke
				(width 0.1)
				(type default)
			)
			(layer "F.Fab")
		)
		(fp_line
			(start 0.299974 0.150114)
			(end -0.299974 0.150114)
			(stroke
				(width 0.1)
				(type default)
			)
			(layer "F.Fab")
		)
		(fp_line
			(start -0.299974 -0.150114)
			(end 0.299974 -0.150114)
			(stroke
				(width 0.1)
				(type default)
			)
			(layer "F.Fab")
		)
		(fp_line
			(start 0.299974 -0.150114)
			(end 0.299974 0.150114)
			(stroke
				(width 0.1)
				(type default)
			)
			(layer "F.Fab")
		)
		(pad "1" smd rect
			(at -0.2667 0 270)
			(size 0.3048 0.381)
			(layers "F.Cu" "F.Mask" "F.Paste")
			(net "P5E_CPU0_PE3_TX_C_DP<12>")
		)
		(pad "2" smd rect
			(at 0.2667 0 270)
			(size 0.3048 0.381)
			(layers "F.Cu" "F.Mask" "F.Paste")
			(net "P5E_CPU0_PE3_TX_DP<12>")
		)
	)
	(footprint ""
		(layer "F.Cu")
		(at 89.535 -32.070548)
		(property "Reference" "U321"
			(at -2.2606 -2.352548 0)
			(unlocked yes)
			(layer "F.SilkS")
			(effects
				(font
					(size 0.7874 0.5842)
					(thickness 0.1524)
				)
				(justify left)
			)
		)
		(property "Value" ""
			(at 0 0 0)
			(layer "F.Fab")
			(effects
				(font
					(size 1.27 1.27)
				)
			)
		)
		(duplicate_pad_numbers_are_jumpers no)
		(fp_line
			(start -2.032 -1.549908)
			(end 2.032 -1.549908)
			(stroke
				(width 0.1524)
				(type default)
			)
			(layer "F.SilkS")
		)
		(fp_line
			(start -2.032 1.549908)
			(end -2.032 -1.549908)
			(stroke
				(width 0.1524)
				(type default)
			)
			(layer "F.SilkS")
		)
		(fp_line
			(start 2.032 -1.549908)
			(end 2.032 1.549908)
			(stroke
				(width 0.1524)
				(type default)
			)
			(layer "F.SilkS")
		)
		(fp_line
			(start 2.032 1.549908)
			(end -2.032 1.549908)
			(stroke
				(width 0.1524)
				(type default)
			)
			(layer "F.SilkS")
		)
		(fp_poly
			(pts
				(xy -2.9464 -1.2192) (xy -2.9464 -0.7112) (xy -2.1844 -0.9652)
			)
			(stroke
				(width 0)
				(type default)
			)
			(fill yes)
			(layer "F.SilkS")
		)
		(fp_line
			(start -0.849884 -1.549908)
			(end -0.849884 1.549908)
			(stroke
				(width 0.1)
				(type default)
			)
			(layer "F.Fab")
		)
		(fp_line
			(start -0.849884 1.549908)
			(end 0.849884 1.549908)
			(stroke
				(width 0.1)
				(type default)
			)
			(layer "F.Fab")
		)
		(fp_line
			(start 0.849884 -1.549908)
			(end -0.849884 -1.549908)
			(stroke
				(width 0.1)
				(type default)
			)
			(layer "F.Fab")
		)
		(fp_line
			(start 0.849884 1.549908)
			(end 0.849884 -1.549908)
			(stroke
				(width 0.1)
				(type default)
			)
			(layer "F.Fab")
		)
		(fp_poly
			(pts
				(xy -2.9464 -1.2192) (xy -2.9464 -0.7112) (xy -2.1844 -0.9652)
			)
			(stroke
				(width 0)
				(type default)
			)
			(fill yes)
			(layer "F.Fab")
		)
		(pad "1" smd rect
			(at -1.225042 -0.94996 270)
			(size 0.4572 1.3208)
			(layers "F.Cu" "F.Mask" "F.Paste")
			(net "CLK_50M_NCSI_OCP_V3_2")
		)
		(pad "2" smd rect
			(at -1.225042 0 270)
			(size 0.4572 1.3208)
			(layers "F.Cu" "F.Mask" "F.Paste")
			(net "CLK_50M_NCSI_OCP_V3_2_ISO_R")
		)
		(pad "3" smd rect
			(at -1.225042 0.94996 270)
			(size 0.4572 1.3208)
			(layers "F.Cu" "F.Mask" "F.Paste")
			(net "GND")
		)
		(pad "4" smd rect
			(at 1.225042 0.94996 270)
			(size 0.4572 1.3208)
			(layers "F.Cu" "F.Mask" "F.Paste")
			(net "FB_BMC_ISOLATE1")
		)
		(pad "5" smd rect
			(at 1.225042 -0.94996 270)
			(size 0.4572 1.3208)
			(layers "F.Cu" "F.Mask" "F.Paste")
			(net "P3V3_AUX")
		)
	)
)
